(kicad_pcb
	(version 20241229)
	(generator "pcbnew")
	(generator_version "9.0")
	(general
		(thickness 1.711)
		(legacy_teardrops no)
	)
	(paper "A4")
	(title_block
		(title "Antmicro Baseboard for Jetson AGX Thor")
		(date "2026-02-18")
		(rev "1.1.0")
		(company "Antmicro Ltd")
		(comment 1 "www.antmicro.com")
		(comment 9 "footprints 28-32 of 1170")
	)
	(layers
		(0 "F.Cu" signal)
		(4 "In1.Cu" signal)
		(6 "In2.Cu" signal)
		(8 "In3.Cu" signal)
		(10 "In4.Cu" jumper)
		(12 "In5.Cu" signal)
		(14 "In6.Cu" signal)
		(16 "In7.Cu" signal)
		(18 "In8.Cu" signal)
		(2 "B.Cu" signal)
		(9 "F.Adhes" user "F.Adhesive")
		(11 "B.Adhes" user "B.Adhesive")
		(13 "F.Paste" user)
		(15 "B.Paste" user)
		(5 "F.SilkS" user "F.Silkscreen")
		(7 "B.SilkS" user "B.Silkscreen")
		(1 "F.Mask" user)
		(3 "B.Mask" user)
		(17 "Dwgs.User" user "User.Drawings")
		(19 "Cmts.User" user "User.Comments")
		(21 "Eco1.User" user "User.Eco1")
		(23 "Eco2.User" user "User.Eco2")
		(25 "Edge.Cuts" user)
		(27 "Margin" user)
		(31 "F.CrtYd" user "F.Courtyard")
		(29 "B.CrtYd" user "B.Courtyard")
		(35 "F.Fab" user)
		(33 "B.Fab" user)
	)
	(footprint "antmicro-footprints:R_0402_1005Metric"
		(layer "F.Cu")
		(at 147 113)
		(descr "Resistor SMD 0402")
		(tags "resistor SMD 0402")
		(property "Reference" "R354"
			(at -3.6 0.4 0)
			(layer "F.SilkS")
			(effects
				(font
					(size 0.7 0.7)
					(thickness 0.15)
				)
				(justify left bottom)
			)
		)
		(property "Value" "R_2k2_0402"
			(at -1.011843 1.772047 0)
			(layer "F.Fab")
			(effects
				(font
					(size 0.7 0.7)
					(thickness 0.15)
				)
				(justify left bottom)
			)
		)
		(property "Datasheet" "https://www.bourns.com/docs/product-datasheets/cr.pdf"
			(at 0 0 0)
			(layer "F.Fab")
			(hide yes)
			(effects
				(font
					(size 1.27 1.27)
					(thickness 0.15)
				)
			)
		)
		(property "Description" "SMD Chip Resistor, 2.2 kohm, ± 1%, 62.5 mW, 0402 [1005 Metric], Thick Film, General Purpose"
			(at 0 0 0)
			(layer "F.Fab")
			(hide yes)
			(effects
				(font
					(size 1.27 1.27)
					(thickness 0.15)
				)
			)
		)
		(property "MPN" "CR0402-FX-2201GLF"
			(at 0 0 0)
			(unlocked yes)
			(layer "F.Fab")
			(hide yes)
			(effects
				(font
					(size 1 1)
					(thickness 0.15)
				)
			)
		)
		(property "Manufacturer" "Bourns"
			(at 0 0 0)
			(unlocked yes)
			(layer "F.Fab")
			(hide yes)
			(effects
				(font
					(size 1 1)
					(thickness 0.15)
				)
			)
		)
		(property "License" "Apache-2.0"
			(at 0 0 0)
			(unlocked yes)
			(layer "F.Fab")
			(hide yes)
			(effects
				(font
					(size 1 1)
					(thickness 0.15)
				)
			)
		)
		(property "Author" "Antmicro"
			(at 0 0 0)
			(unlocked yes)
			(layer "F.Fab")
			(hide yes)
			(effects
				(font
					(size 1 1)
					(thickness 0.15)
				)
			)
		)
		(property "Val" "2k2"
			(at 0 0 0)
			(unlocked yes)
			(layer "F.Fab")
			(hide yes)
			(effects
				(font
					(size 1 1)
					(thickness 0.15)
				)
			)
		)
		(property "Tolerance" "1%"
			(at 0 0 0)
			(unlocked yes)
			(layer "F.Fab")
			(hide yes)
			(effects
				(font
					(size 1 1)
					(thickness 0.15)
				)
			)
		)
		(sheetname "/SoM_IO/")
		(sheetfile "som_io.kicad_sch")
		(attr smd exclude_from_pos_files exclude_from_bom dnp)
		(fp_rect
			(start -0.925 -0.47)
			(end 0.925 0.47)
			(stroke
				(width 0.05)
				(type default)
			)
			(fill no)
			(layer "F.CrtYd")
		)
		(fp_rect
			(start -0.5 -0.25)
			(end 0.5 0.25)
			(stroke
				(width 0.15)
				(type solid)
			)
			(fill no)
			(layer "F.Fab")
		)
		(fp_text user "License: Apache-2.0"
			(at -0.95 5.169 0)
			(layer "F.Fab")
			(effects
				(font
					(size 0.7 0.7)
					(thickness 0.15)
				)
				(justify left bottom)
			)
		)
		(fp_text user "${REFERENCE}"
			(at -0.95 3.168 0)
			(layer "F.Fab")
			(effects
				(font
					(size 0.7 0.7)
					(thickness 0.15)
				)
				(justify left bottom)
			)
		)
		(fp_text user "Author: Antmicro"
			(at -0.95 4.169 0)
			(layer "F.Fab")
			(effects
				(font
					(size 0.7 0.7)
					(thickness 0.15)
				)
				(justify left bottom)
			)
		)
		(pad "1" smd roundrect
			(at -0.48 0)
			(size 0.59 0.64)
			(layers "F.Cu" "F.Mask" "F.Paste")
			(roundrect_rratio 0.25)
			(net 11 "+1V8")
			(pintype "passive")
		)
		(pad "2" smd roundrect
			(at 0.48 0)
			(size 0.59 0.64)
			(layers "F.Cu" "F.Mask" "F.Paste")
			(roundrect_rratio 0.25)
			(net 112 "/SoM_IO/I2C5_SDA_1V8")
			(pintype "passive")
		)
	)
	(footprint "antmicro-footprints:R_0402_1005Metric"
		(layer "F.Cu")
		(at 147.8 120.2)
		(descr "Resistor SMD 0402")
		(tags "resistor SMD 0402")
		(property "Reference" "R374"
			(at -3.7 0.5 0)
			(layer "F.SilkS")
			(effects
				(font
					(size 0.7 0.7)
					(thickness 0.15)
				)
				(justify left bottom)
			)
		)
		(property "Value" "R_2k2_0402"
			(at -1.011843 1.772047 0)
			(layer "F.Fab")
			(effects
				(font
					(size 0.7 0.7)
					(thickness 0.15)
				)
				(justify left bottom)
			)
		)
		(property "Datasheet" "https://www.bourns.com/docs/product-datasheets/cr.pdf"
			(at 0 0 0)
			(layer "F.Fab")
			(hide yes)
			(effects
				(font
					(size 1.27 1.27)
					(thickness 0.15)
				)
			)
		)
		(property "Description" "SMD Chip Resistor, 2.2 kohm, ± 1%, 62.5 mW, 0402 [1005 Metric], Thick Film, General Purpose"
			(at 0 0 0)
			(layer "F.Fab")
			(hide yes)
			(effects
				(font
					(size 1.27 1.27)
					(thickness 0.15)
				)
			)
		)
		(property "MPN" "CR0402-FX-2201GLF"
			(at 0 0 0)
			(unlocked yes)
			(layer "F.Fab")
			(hide yes)
			(effects
				(font
					(size 1 1)
					(thickness 0.15)
				)
			)
		)
		(property "Manufacturer" "Bourns"
			(at 0 0 0)
			(unlocked yes)
			(layer "F.Fab")
			(hide yes)
			(effects
				(font
					(size 1 1)
					(thickness 0.15)
				)
			)
		)
		(property "License" "Apache-2.0"
			(at 0 0 0)
			(unlocked yes)
			(layer "F.Fab")
			(hide yes)
			(effects
				(font
					(size 1 1)
					(thickness 0.15)
				)
			)
		)
		(property "Author" "Antmicro"
			(at 0 0 0)
			(unlocked yes)
			(layer "F.Fab")
			(hide yes)
			(effects
				(font
					(size 1 1)
					(thickness 0.15)
				)
			)
		)
		(property "Val" "2k2"
			(at 0 0 0)
			(unlocked yes)
			(layer "F.Fab")
			(hide yes)
			(effects
				(font
					(size 1 1)
					(thickness 0.15)
				)
			)
		)
		(property "Tolerance" "1%"
			(at 0 0 0)
			(unlocked yes)
			(layer "F.Fab")
			(hide yes)
			(effects
				(font
					(size 1 1)
					(thickness 0.15)
				)
			)
		)
		(sheetname "/SoM_IO/")
		(sheetfile "som_io.kicad_sch")
		(attr smd)
		(fp_rect
			(start -0.925 -0.47)
			(end 0.925 0.47)
			(stroke
				(width 0.05)
				(type default)
			)
			(fill no)
			(layer "F.CrtYd")
		)
		(fp_rect
			(start -0.5 -0.25)
			(end 0.5 0.25)
			(stroke
				(width 0.15)
				(type solid)
			)
			(fill no)
			(layer "F.Fab")
		)
		(fp_text user "License: Apache-2.0"
			(at -0.95 5.169 0)
			(layer "F.Fab")
			(effects
				(font
					(size 0.7 0.7)
					(thickness 0.15)
				)
				(justify left bottom)
			)
		)
		(fp_text user "Author: Antmicro"
			(at -0.95 4.169 0)
			(layer "F.Fab")
			(effects
				(font
					(size 0.7 0.7)
					(thickness 0.15)
				)
				(justify left bottom)
			)
		)
		(fp_text user "${REFERENCE}"
			(at -0.95 3.168 0)
			(layer "F.Fab")
			(effects
				(font
					(size 0.7 0.7)
					(thickness 0.15)
				)
				(justify left bottom)
			)
		)
		(pad "1" smd roundrect
			(at -0.48 0)
			(size 0.59 0.64)
			(layers "F.Cu" "F.Mask" "F.Paste")
			(roundrect_rratio 0.25)
			(net 2 "+3V3")
			(pintype "passive")
		)
		(pad "2" smd roundrect
			(at 0.48 0)
			(size 0.59 0.64)
			(layers "F.Cu" "F.Mask" "F.Paste")
			(roundrect_rratio 0.25)
			(net 407 "/Expansion connector/I2C0.SCL")
			(pintype "passive")
		)
	)
	(footprint "antmicro-footprints:C_0805_2012Metric"
		(layer "F.Cu")
		(at 130.129998 55.68 180)
		(descr "Capacitor SMD 0805")
		(tags "capacitor SMD 0805")
		(property "Reference" "C371"
			(at 9.919998 -9.73 0)
			(layer "F.SilkS")
			(effects
				(font
					(size 0.7 0.7)
					(thickness 0.15)
				)
				(justify left bottom)
			)
		)
		(property "Value" "C_22u_25V_0805"
			(at -2.055717 1.963153 0)
			(layer "F.Fab")
			(effects
				(font
					(size 0.7 0.7)
					(thickness 0.15)
				)
				(justify right top)
			)
		)
		(property "Datasheet" "https://product.samsungsem.com/mlcc/CL21A226MAYNNN.do"
			(at 0 0 0)
			(layer "F.Fab")
			(hide yes)
			(effects
				(font
					(size 1.27 1.27)
					(thickness 0.15)
				)
			)
		)
		(property "Description" "SMT Multilayer Ceramic Capacitor, 22uF, +/-20%, 25V, X5R, 0805 [2012 Metric]"
			(at 0 0 0)
			(layer "F.Fab")
			(hide yes)
			(effects
				(font
					(size 1.27 1.27)
					(thickness 0.15)
				)
			)
		)
		(property "MPN" "CL21A226MAYNNNE"
			(at 0 0 180)
			(unlocked yes)
			(layer "F.Fab")
			(hide yes)
			(effects
				(font
					(size 1 1)
					(thickness 0.15)
				)
			)
		)
		(property "Manufacturer" "Samsung Electro-Mechanics"
			(at 0 0 180)
			(unlocked yes)
			(layer "F.Fab")
			(hide yes)
			(effects
				(font
					(size 1 1)
					(thickness 0.15)
				)
			)
		)
		(property "License" "Apache-2.0"
			(at 0 0 180)
			(unlocked yes)
			(layer "F.Fab")
			(hide yes)
			(effects
				(font
					(size 1 1)
					(thickness 0.15)
				)
			)
		)
		(property "Author" "Antmicro"
			(at 0 0 180)
			(unlocked yes)
			(layer "F.Fab")
			(hide yes)
			(effects
				(font
					(size 1 1)
					(thickness 0.15)
				)
			)
		)
		(property "Val" "22u"
			(at 0 0 180)
			(unlocked yes)
			(layer "F.Fab")
			(hide yes)
			(effects
				(font
					(size 1 1)
					(thickness 0.15)
				)
			)
		)
		(property "Voltage" "25V"
			(at 0 0 180)
			(unlocked yes)
			(layer "F.Fab")
			(hide yes)
			(effects
				(font
					(size 1 1)
					(thickness 0.15)
				)
			)
		)
		(property "Dielectric" "X5R"
			(at 0 0 180)
			(unlocked yes)
			(layer "F.Fab")
			(hide yes)
			(effects
				(font
					(size 1 1)
					(thickness 0.15)
				)
			)
		)
		(property "Public" "False"
			(at 0 0 180)
			(unlocked yes)
			(layer "F.Fab")
			(hide yes)
			(effects
				(font
					(size 1 1)
					(thickness 0.15)
				)
			)
		)
		(sheetname "/DCDC/")
		(sheetfile "dcdc.kicad_sch")
		(attr smd)
		(fp_line
			(start -0.3 0.7)
			(end 0.3 0.7)
			(stroke
				(width 0.15)
				(type solid)
			)
			(layer "F.SilkS")
		)
		(fp_line
			(start -0.3 -0.7)
			(end 0.3 -0.7)
			(stroke
				(width 0.15)
				(type solid)
			)
			(layer "F.SilkS")
		)
		(fp_poly
			(pts
				(xy 1.95 -0.9) (xy 1.95 0.9) (xy -1.95 0.9) (xy -1.95 -0.9)
			)
			(stroke
				(width 0.05)
				(type default)
			)
			(fill no)
			(layer "F.CrtYd")
		)
		(fp_poly
			(pts
				(xy -0.95 -0.675001) (xy -0.95 0.675001) (xy 0.95 0.675001) (xy 0.95 -0.675001)
			)
			(stroke
				(width 0.15)
				(type solid)
			)
			(fill no)
			(layer "F.Fab")
		)
		(fp_text user "License: Apache-2.0"
			(at -1.9 4.947 0)
			(layer "F.Fab")
			(effects
				(font
					(size 0.7 0.7)
					(thickness 0.15)
				)
				(justify right top)
			)
		)
		(fp_text user "${REFERENCE}"
			(at -1.899999 3.947 0)
			(layer "F.Fab")
			(effects
				(font
					(size 0.7 0.7)
					(thickness 0.15)
				)
				(justify right top)
			)
		)
		(fp_text user "Author: Antmicro"
			(at -1.9 5.947 0)
			(layer "F.Fab")
			(effects
				(font
					(size 0.7 0.7)
					(thickness 0.15)
				)
				(justify right top)
			)
		)
		(pad "1" smd roundrect
			(at -1.099999 0 180)
			(size 1.2 1.3)
			(layers "F.Cu" "F.Mask" "F.Paste")
			(roundrect_rratio 0.25)
			(net 1 "GND")
			(pintype "passive")
		)
		(pad "2" smd roundrect
			(at 1.099999 0 180)
			(size 1.2 1.3)
			(layers "F.Cu" "F.Mask" "F.Paste")
			(roundrect_rratio 0.25)
			(net 13 "VCC")
			(pintype "passive")
		)
	)
	(footprint "antmicro-footprints:C_0402_1005Metric"
		(layer "F.Cu")
		(at 217.2 94.2)
		(descr "Capacitor SMD 0402")
		(tags "capacitor SMD 0402")
		(property "Reference" "C131"
			(at -0.5 1.5 0)
			(layer "F.SilkS")
			(effects
				(font
					(size 0.7 0.7)
					(thickness 0.15)
				)
				(justify left bottom)
			)
		)
		(property "Value" "C_100n_0402"
			(at -1.022927 2.155213 0)
			(layer "F.Fab")
			(effects
				(font
					(size 0.7 0.7)
					(thickness 0.15)
				)
				(justify left bottom)
			)
		)
		(property "Datasheet" "https://www.murata.com/products/productdetail?partno=GRM155R61H104KE14%23"
			(at 0 0 0)
			(layer "F.Fab")
			(hide yes)
			(effects
				(font
					(size 1.27 1.27)
					(thickness 0.15)
				)
			)
		)
		(property "Description" "SMD Multilayer Ceramic Capacitor, 0.1 µF, 50 V, 0402 [1005 Metric], ± 10%, X5R, GRM Series"
			(at 0 0 0)
			(layer "F.Fab")
			(hide yes)
			(effects
				(font
					(size 1.27 1.27)
					(thickness 0.15)
				)
			)
		)
		(property "Manufacturer" "Murata"
			(at 0 0 0)
			(unlocked yes)
			(layer "F.Fab")
			(hide yes)
			(effects
				(font
					(size 1 1)
					(thickness 0.15)
				)
			)
		)
		(property "MPN" "GRM155R61H104KE14D"
			(at 0 0 0)
			(unlocked yes)
			(layer "F.Fab")
			(hide yes)
			(effects
				(font
					(size 1 1)
					(thickness 0.15)
				)
			)
		)
		(property "Val" "100n"
			(at 0 0 0)
			(unlocked yes)
			(layer "F.Fab")
			(hide yes)
			(effects
				(font
					(size 1 1)
					(thickness 0.15)
				)
			)
		)
		(property "License" "Apache-2.0"
			(at 0 0 0)
			(unlocked yes)
			(layer "F.Fab")
			(hide yes)
			(effects
				(font
					(size 1 1)
					(thickness 0.15)
				)
			)
		)
		(property "Author" "Antmicro"
			(at 0 0 0)
			(unlocked yes)
			(layer "F.Fab")
			(hide yes)
			(effects
				(font
					(size 1 1)
					(thickness 0.15)
				)
			)
		)
		(property "Voltage" "50V"
			(at 0 0 0)
			(unlocked yes)
			(layer "F.Fab")
			(hide yes)
			(effects
				(font
					(size 1 1)
					(thickness 0.15)
				)
			)
		)
		(property "Dielectric" "X5R"
			(at 0 0 0)
			(unlocked yes)
			(layer "F.Fab")
			(hide yes)
			(effects
				(font
					(size 1 1)
					(thickness 0.15)
				)
			)
		)
		(sheetname "/USB DP Alt mode/")
		(sheetfile "usb_dp.kicad_sch")
		(attr smd)
		(fp_poly
			(pts
				(xy -0.925 -0.47) (xy -0.925 0.47) (xy 0.925 0.47) (xy 0.925 -0.47)
			)
			(stroke
				(width 0.05)
				(type default)
			)
			(fill no)
			(layer "F.CrtYd")
		)
		(fp_line
			(start -0.494 -0.25)
			(end 0.504 -0.25)
			(stroke
				(width 0.15)
				(type solid)
			)
			(layer "F.Fab")
		)
		(fp_line
			(start -0.494 0.248)
			(end -0.494 -0.25)
			(stroke
				(width 0.15)
				(type solid)
			)
			(layer "F.Fab")
		)
		(fp_line
			(start 0.504 -0.25)
			(end 0.504 0.248)
			(stroke
				(width 0.15)
				(type solid)
			)
			(layer "F.Fab")
		)
		(fp_line
			(start 0.504 0.248)
			(end -0.494 0.248)
			(stroke
				(width 0.15)
				(type solid)
			)
			(layer "F.Fab")
		)
		(fp_text user "License: Apache-2.0"
			(at -0.939 5.799 0)
			(layer "F.Fab")
			(effects
				(font
					(size 0.7 0.7)
					(thickness 0.15)
				)
				(justify left bottom)
			)
		)
		(fp_text user "${REFERENCE}"
			(at -0.939 4.599 0)
			(layer "F.Fab")
			(effects
				(font
					(size 0.7 0.7)
					(thickness 0.15)
				)
				(justify left bottom)
			)
		)
		(fp_text user "Author: Antmicro"
			(at -0.939 3.399 0)
			(layer "F.Fab")
			(effects
				(font
					(size 0.7 0.7)
					(thickness 0.15)
				)
				(justify left bottom)
			)
		)
		(pad "1" smd roundrect
			(at -0.48 0)
			(size 0.59 0.64)
			(layers "F.Cu" "F.Mask" "F.Paste")
			(roundrect_rratio 0.25)
			(net 2 "+3V3")
			(pintype "passive")
		)
		(pad "2" smd roundrect
			(at 0.48 0)
			(size 0.59 0.64)
			(layers "F.Cu" "F.Mask" "F.Paste")
			(roundrect_rratio 0.25)
			(net 1 "GND")
			(pintype "passive")
		)
	)
	(footprint "antmicro-footprints:R_0402_1005Metric"
		(layer "F.Cu")
		(at 92.98 149.18)
		(descr "Resistor SMD 0402")
		(tags "resistor SMD 0402")
		(property "Reference" "R196"
			(at 1.02 0.394264 0)
			(layer "F.SilkS")
			(effects
				(font
					(size 0.7 0.7)
					(thickness 0.15)
				)
				(justify left bottom)
			)
		)
		(property "Value" "R_0R_0402"
			(at -1.011843 1.772046 0)
			(layer "F.Fab")
			(effects
				(font
					(size 0.7 0.7)
					(thickness 0.15)
				)
				(justify left bottom)
			)
		)
		(property "Datasheet" "https://industrial.panasonic.com/cdbs/www-data/pdf/RDA0000/AOA0000C301.pdf"
			(at 0 0 0)
			(layer "F.Fab")
			(hide yes)
			(effects
				(font
					(size 1.27 1.27)
					(thickness 0.15)
				)
			)
		)
		(property "Description" "SMD Chip Resistor, Jumper, 0 ohm, 100 mW, 0402 [1005 Metric], Thick Film, General Purpose"
			(at 0 0 0)
			(layer "F.Fab")
			(hide yes)
			(effects
				(font
					(size 1.27 1.27)
					(thickness 0.15)
				)
			)
		)
		(property "MPN" "ERJ2GE0R00X"
			(at 0 0 0)
			(unlocked yes)
			(layer "F.Fab")
			(hide yes)
			(effects
				(font
					(size 1 1)
					(thickness 0.15)
				)
			)
		)
		(property "Manufacturer" "Panasonic"
			(at 0 0 0)
			(unlocked yes)
			(layer "F.Fab")
			(hide yes)
			(effects
				(font
					(size 1 1)
					(thickness 0.15)
				)
			)
		)
		(property "License" "Apache-2.0"
			(at 0 0 0)
			(unlocked yes)
			(layer "F.Fab")
			(hide yes)
			(effects
				(font
					(size 1 1)
					(thickness 0.15)
				)
			)
		)
		(property "Author" "Antmicro"
			(at 0 0 0)
			(unlocked yes)
			(layer "F.Fab")
			(hide yes)
			(effects
				(font
					(size 1 1)
					(thickness 0.15)
				)
			)
		)
		(property "Val" "0R"
			(at 0 0 0)
			(unlocked yes)
			(layer "F.Fab")
			(hide yes)
			(effects
				(font
					(size 1 1)
					(thickness 0.15)
				)
			)
		)
		(property "Tolerance" "~"
			(at 0 0 0)
			(unlocked yes)
			(layer "F.Fab")
			(hide yes)
			(effects
				(font
					(size 1 1)
					(thickness 0.15)
				)
			)
		)
		(property "Current" "1A"
			(at 0 0 0)
			(unlocked yes)
			(layer "F.Fab")
			(hide yes)
			(effects
				(font
					(size 1 1)
					(thickness 0.15)
				)
			)
		)
		(sheetname "/SoM_IO2/")
		(sheetfile "som_io2.kicad_sch")
		(attr smd exclude_from_pos_files exclude_from_bom dnp)
		(fp_poly
			(pts
				(xy -0.925 -0.47) (xy -0.925 0.47) (xy 0.925 0.47) (xy 0.925 -0.47)
			)
			(stroke
				(width 0.05)
				(type default)
			)
			(fill no)
			(layer "F.CrtYd")
		)
		(fp_poly
			(pts
				(xy -0.5 -0.25) (xy -0.5 0.25) (xy 0.5 0.25) (xy 0.5 -0.25)
			)
			(stroke
				(width 0.15)
				(type solid)
			)
			(fill no)
			(layer "F.Fab")
		)
		(fp_text user "License: Apache-2.0"
			(at -0.949999 5.169 0)
			(layer "F.Fab")
			(effects
				(font
					(size 0.7 0.7)
					(thickness 0.15)
				)
				(justify left bottom)
			)
		)
		(fp_text user "${REFERENCE}"
			(at -0.95 3.168 0)
			(layer "F.Fab")
			(effects
				(font
					(size 0.7 0.7)
					(thickness 0.15)
				)
				(justify left bottom)
			)
		)
		(fp_text user "Author: Antmicro"
			(at -0.95 4.169 0)
			(layer "F.Fab")
			(effects
				(font
					(size 0.7 0.7)
					(thickness 0.15)
				)
				(justify left bottom)
			)
		)
		(pad "1" smd roundrect
			(at -0.48 0)
			(size 0.59 0.64)
			(layers "F.Cu" "F.Mask" "F.Paste")
			(roundrect_rratio 0.25)
			(net 898 "/SoM_IO2/C2_REFCLK+")
			(pintype "passive")
		)
		(pad "2" smd roundrect
			(at 0.48 0)
			(size 0.59 0.64)
			(layers "F.Cu" "F.Mask" "F.Paste")
			(roundrect_rratio 0.25)
			(net 720 "/SoM_IO2/PCIe_{C2x1}R_CLK+")
			(pintype "passive")
		)
	)
)
